(kicad_pcb
	(version 20260206)
	(generator "pcbnew")
	(generator_version "10.0")
	(general
		(thickness 1.6)
		(legacy_teardrops no)
	)
	(paper "A4")
	(title_block
		(title "12092022_DA0F0TFB6D0_F0T_FAN_BOARD_MP5048_D_brd_v02_OCP.brd")
		(comment 1 "Grand Teton / footprints 759-764 of 924")
	)
	(layers
		(0 "F.Cu" signal "TOP")
		(4 "In1.Cu" signal "GND")
		(6 "In2.Cu" signal "IN1")
		(8 "In3.Cu" signal "IN2")
		(10 "In4.Cu" signal "GND1")
		(2 "B.Cu" signal "BOTTOM")
		(9 "F.Adhes" user "F.Adhesive")
		(11 "B.Adhes" user "B.Adhesive")
		(13 "F.Paste" user "Package Geometry/Pastemask Top")
		(15 "B.Paste" user "Package Geometry/Pastemask Bottom")
		(5 "F.SilkS" user "Ref Des/Silkscreen Top")
		(7 "B.SilkS" user "Ref Des/Silkscreen Bottom")
		(1 "F.Mask" user "Board Geometry/Soldermask Top")
		(3 "B.Mask" user "Board Geometry/Soldermask Bottom")
		(17 "Dwgs.User" user "User.Drawings")
		(19 "Cmts.User" user "User.Comments")
		(21 "Eco1.User" user "User.Eco1")
		(23 "Eco2.User" user "User.Eco2")
		(25 "Edge.Cuts" user "Board Geometry/Outline")
		(27 "Margin" user)
		(31 "F.CrtYd" user "Package Geometry/Place Bound Top")
		(29 "B.CrtYd" user "Package Geometry/Place Bound Bottom")
		(35 "F.Fab" user "Ref Des/Assembly Top")
		(33 "B.Fab" user "Ref Des/Assembly Bottom")
	)
	(footprint ""
		(layer "B.Cu")
		(at 7.947914 -67.494912 180)
		(property "Reference" "U359"
			(at -0.053086 1.820418 0)
			(unlocked yes)
			(layer "B.SilkS")
			(effects
				(font
					(size 0.7874 0.5842)
					(thickness 0.1524)
				)
				(justify mirror)
			)
		)
		(property "Value" ""
			(at 0 0 0)
			(layer "B.Fab")
			(effects
				(font
					(size 1.27 1.27)
				)
				(justify mirror)
			)
		)
		(duplicate_pad_numbers_are_jumpers no)
		(fp_line
			(start 1.7018 1.1176)
			(end 1.7018 -1.1176)
			(stroke
				(width 0.1524)
				(type default)
			)
			(layer "B.SilkS")
		)
		(fp_line
			(start 0.254 -1.1176)
			(end 1.7018 -1.1176)
			(stroke
				(width 0.1524)
				(type default)
			)
			(layer "B.SilkS")
		)
		(fp_line
			(start 0 -0.7112)
			(end 0.254 -1.1176)
			(stroke
				(width 0.1524)
				(type default)
			)
			(layer "B.SilkS")
		)
		(fp_line
			(start -0.254 -1.1176)
			(end 0 -0.7112)
			(stroke
				(width 0.1524)
				(type default)
			)
			(layer "B.SilkS")
		)
		(fp_line
			(start -1.7018 1.1176)
			(end 1.7018 1.1176)
			(stroke
				(width 0.1524)
				(type default)
			)
			(layer "B.SilkS")
		)
		(fp_line
			(start -1.7018 -1.1176)
			(end -0.254 -1.1176)
			(stroke
				(width 0.1524)
				(type default)
			)
			(layer "B.SilkS")
		)
		(fp_line
			(start -1.7018 -1.1176)
			(end -1.7018 1.1176)
			(stroke
				(width 0.1524)
				(type default)
			)
			(layer "B.SilkS")
		)
		(fp_poly
			(pts
				(xy 1.8161 -0.802386) (xy 2.4003 -0.573786) (xy 2.4003 -1.005586)
			)
			(stroke
				(width 0)
				(type default)
			)
			(fill yes)
			(layer "B.SilkS")
		)
		(fp_line
			(start 1.5494 1.1176)
			(end 1.5494 -1.1176)
			(stroke
				(width 0.1)
				(type default)
			)
			(layer "B.Fab")
		)
		(fp_line
			(start 0.254 -1.1176)
			(end 1.5494 -1.1176)
			(stroke
				(width 0.1)
				(type default)
			)
			(layer "B.Fab")
		)
		(fp_line
			(start -0.254 -1.1176)
			(end 0.254 -1.1176)
			(stroke
				(width 0.1)
				(type default)
			)
			(layer "B.Fab")
		)
		(fp_line
			(start -1.5494 1.1176)
			(end 1.5494 1.1176)
			(stroke
				(width 0.1)
				(type default)
			)
			(layer "B.Fab")
		)
		(fp_line
			(start -1.5494 -1.1176)
			(end -0.254 -1.1176)
			(stroke
				(width 0.1)
				(type default)
			)
			(layer "B.Fab")
		)
		(fp_line
			(start -1.5494 -1.1176)
			(end -1.5494 1.1176)
			(stroke
				(width 0.1)
				(type default)
			)
			(layer "B.Fab")
		)
		(fp_poly
			(pts
				(xy 1.8161 -0.675386) (xy 2.4003 -0.446786) (xy 2.4003 -0.878586)
			)
			(stroke
				(width 0)
				(type default)
			)
			(fill yes)
			(layer "B.Fab")
		)
		(pad "1" smd rect
			(at 0.962406 -0.649986 90)
			(size 0.3302 1.1684)
			(layers "B.Cu" "B.Mask" "B.Paste")
			(net "FAN_4_PRESENT_R")
		)
		(pad "2" smd rect
			(at 0.962406 0 90)
			(size 0.3302 1.1684)
			(layers "B.Cu" "B.Mask" "B.Paste")
			(net "P52V_FAN_4_BUFF_EN_R")
		)
		(pad "3" smd rect
			(at 0.962406 0.649986 90)
			(size 0.3302 1.1684)
			(layers "B.Cu" "B.Mask" "B.Paste")
			(net "GND")
		)
		(pad "4" smd rect
			(at -0.962406 0.649986 90)
			(size 0.3302 1.1684)
			(layers "B.Cu" "B.Mask" "B.Paste")
			(net "P52V_FAN_4_EN")
		)
		(pad "5" smd rect
			(at -0.962406 -0.649986 90)
			(size 0.3302 1.1684)
			(layers "B.Cu" "B.Mask" "B.Paste")
			(net "P3V3_AUX")
		)
	)
	(footprint ""
		(layer "B.Cu")
		(at 1.778 -64.827912 -90)
		(property "Reference" "PR50"
			(at 0 0 90)
			(layer "B.SilkS")
			(hide yes)
			(effects
				(font
					(size 1.27 1.27)
				)
				(justify mirror)
			)
		)
		(property "Value" ""
			(at 0 0 90)
			(layer "B.Fab")
			(effects
				(font
					(size 1.27 1.27)
				)
				(justify mirror)
			)
		)
		(duplicate_pad_numbers_are_jumpers no)
		(fp_line
			(start -0.7874 0.4064)
			(end 0.7874 0.4064)
			(stroke
				(width 0.1524)
				(type default)
			)
			(layer "B.SilkS")
		)
		(fp_line
			(start 0.7874 0.4064)
			(end 0.7874 -0.4064)
			(stroke
				(width 0.1524)
				(type default)
			)
			(layer "B.SilkS")
		)
		(fp_line
			(start -0.7874 -0.4064)
			(end -0.7874 0.4064)
			(stroke
				(width 0.1524)
				(type default)
			)
			(layer "B.SilkS")
		)
		(fp_line
			(start 0.7874 -0.4064)
			(end -0.7874 -0.4064)
			(stroke
				(width 0.1524)
				(type default)
			)
			(layer "B.SilkS")
		)
		(fp_line
			(start -0.67945 0.3048)
			(end -0.120396 0.3048)
			(stroke
				(width 0.1)
				(type default)
			)
			(layer "B.Fab")
		)
		(fp_line
			(start -0.120396 0.3048)
			(end -0.120396 0.2794)
			(stroke
				(width 0.1)
				(type default)
			)
			(layer "B.Fab")
		)
		(fp_line
			(start 0.12065 0.3048)
			(end 0.67945 0.3048)
			(stroke
				(width 0.1)
				(type default)
			)
			(layer "B.Fab")
		)
		(fp_line
			(start 0.67945 0.3048)
			(end 0.67945 -0.305054)
			(stroke
				(width 0.1)
				(type default)
			)
			(layer "B.Fab")
		)
		(fp_line
			(start -0.120396 0.2794)
			(end 0.12065 0.2794)
			(stroke
				(width 0.1)
				(type default)
			)
			(layer "B.Fab")
		)
		(fp_line
			(start 0.12065 0.2794)
			(end 0.12065 0.3048)
			(stroke
				(width 0.1)
				(type default)
			)
			(layer "B.Fab")
		)
		(fp_line
			(start -0.12065 -0.2794)
			(end -0.12065 -0.3048)
			(stroke
				(width 0.1)
				(type default)
			)
			(layer "B.Fab")
		)
		(fp_line
			(start 0.12065 -0.2794)
			(end -0.12065 -0.2794)
			(stroke
				(width 0.1)
				(type default)
			)
			(layer "B.Fab")
		)
		(fp_line
			(start -0.67945 -0.3048)
			(end -0.67945 0.3048)
			(stroke
				(width 0.1)
				(type default)
			)
			(layer "B.Fab")
		)
		(fp_line
			(start -0.12065 -0.3048)
			(end -0.67945 -0.3048)
			(stroke
				(width 0.1)
				(type default)
			)
			(layer "B.Fab")
		)
		(fp_line
			(start 0.12065 -0.305054)
			(end 0.12065 -0.2794)
			(stroke
				(width 0.1)
				(type default)
			)
			(layer "B.Fab")
		)
		(fp_line
			(start 0.67945 -0.305054)
			(end 0.12065 -0.305054)
			(stroke
				(width 0.1)
				(type default)
			)
			(layer "B.Fab")
		)
		(pad "1" smd circle
			(at 0.40005 0 90)
			(size 0 0)
			(layers "B.Cu" "B.Mask" "B.Paste")
			(net "FAN_4_CS")
		)
		(pad "2" smd circle
			(at -0.40005 0 90)
			(size 0 0)
			(layers "B.Cu" "B.Mask" "B.Paste")
			(net "GND")
		)
	)
	(footprint ""
		(layer "B.Cu")
		(at -6.938772 -296.164 180)
		(property "Reference" "J85"
			(at 1.316228 -5.48767 0)
			(unlocked yes)
			(layer "B.SilkS")
			(effects
				(font
					(size 0.7874 0.5842)
					(thickness 0.1524)
				)
				(justify left mirror)
			)
		)
		(property "Value" ""
			(at 0 0 0)
			(layer "B.Fab")
			(effects
				(font
					(size 1.27 1.27)
				)
				(justify mirror)
			)
		)
		(duplicate_pad_numbers_are_jumpers no)
		(fp_line
			(start 3.330702 -4.771136)
			(end -3.330702 -4.771136)
			(stroke
				(width 0.1524)
				(type default)
			)
			(layer "B.SilkS")
		)
		(fp_line
			(start 0 4.011168)
			(end 3.330702 -4.771136)
			(stroke
				(width 0.1524)
				(type default)
			)
			(layer "B.SilkS")
		)
		(fp_line
			(start -3.330702 -4.771136)
			(end 0 4.011168)
			(stroke
				(width 0.1524)
				(type default)
			)
			(layer "B.SilkS")
		)
		(fp_line
			(start 3.330702 -4.771136)
			(end -3.330702 -4.771136)
			(stroke
				(width 0.1)
				(type default)
			)
			(layer "B.Fab")
		)
		(fp_line
			(start 0 4.011168)
			(end 3.330702 -4.771136)
			(stroke
				(width 0.1)
				(type default)
			)
			(layer "B.Fab")
		)
		(fp_line
			(start -3.330702 -4.771136)
			(end 0 4.011168)
			(stroke
				(width 0.1)
				(type default)
			)
			(layer "B.Fab")
		)
		(pad "1" thru_hole circle
			(at 0 0)
			(size 2.159 2.159)
			(drill 1.7018)
			(layers "*.Cu" "*.Mask")
			(remove_unused_layers no)
			(net "GND2")
			(clearance 0.0254)
			(thermal_gap 0.0254)
		)
		(pad "2" thru_hole circle
			(at 1.27 -3.348736)
			(size 2.159 2.159)
			(drill 1.7018)
			(layers "*.Cu" "*.Mask")
			(remove_unused_layers no)
			(net "TDR_SE_50_OHM_IN2")
			(clearance 0.0254)
			(thermal_gap 0.0254)
		)
		(pad "3" thru_hole circle
			(at -1.27 -3.348736)
			(size 2.159 2.159)
			(drill 1.7018)
			(layers "*.Cu" "*.Mask")
			(remove_unused_layers no)
			(net "TDR_SE_50_OHM_IN2")
			(clearance 0.0254)
			(thermal_gap 0.0254)
		)
	)
	(footprint ""
		(layer "B.Cu")
		(at 5.08 -313.182 180)
		(property "Reference" "C2127"
			(at 0 0 0)
			(layer "B.SilkS")
			(hide yes)
			(effects
				(font
					(size 1.27 1.27)
				)
				(justify mirror)
			)
		)
		(property "Value" ""
			(at 0 0 0)
			(layer "B.Fab")
			(effects
				(font
					(size 1.27 1.27)
				)
				(justify mirror)
			)
		)
		(duplicate_pad_numbers_are_jumpers no)
		(fp_line
			(start 1.2954 0.5842)
			(end 1.2954 -0.5842)
			(stroke
				(width 0.1524)
				(type default)
			)
			(layer "B.SilkS")
		)
		(fp_line
			(start 1.2954 -0.5842)
			(end -1.2954 -0.5842)
			(stroke
				(width 0.1524)
				(type default)
			)
			(layer "B.SilkS")
		)
		(fp_line
			(start -1.2954 0.5842)
			(end 1.2954 0.5842)
			(stroke
				(width 0.1524)
				(type default)
			)
			(layer "B.SilkS")
		)
		(fp_line
			(start -1.2954 -0.5842)
			(end -1.2954 0.5842)
			(stroke
				(width 0.1524)
				(type default)
			)
			(layer "B.SilkS")
		)
		(fp_line
			(start 1.1938 0.4064)
			(end 1.1938 -0.4064)
			(stroke
				(width 0.1)
				(type default)
			)
			(layer "B.Fab")
		)
		(fp_line
			(start 1.1938 -0.4064)
			(end 0.8636 -0.4064)
			(stroke
				(width 0.1)
				(type default)
			)
			(layer "B.Fab")
		)
		(fp_line
			(start 0.8636 0.4572)
			(end 0.8636 0.4064)
			(stroke
				(width 0.1)
				(type default)
			)
			(layer "B.Fab")
		)
		(fp_line
			(start 0.8636 0.4064)
			(end 1.1938 0.4064)
			(stroke
				(width 0.1)
				(type default)
			)
			(layer "B.Fab")
		)
		(fp_line
			(start 0.8636 -0.4064)
			(end 0.8636 -0.4572)
			(stroke
				(width 0.1)
				(type default)
			)
			(layer "B.Fab")
		)
		(fp_line
			(start 0.8636 -0.4572)
			(end -0.8636 -0.4572)
			(stroke
				(width 0.1)
				(type default)
			)
			(layer "B.Fab")
		)
		(fp_line
			(start -0.8636 0.4572)
			(end 0.8636 0.4572)
			(stroke
				(width 0.1)
				(type default)
			)
			(layer "B.Fab")
		)
		(fp_line
			(start -0.8636 0.4064)
			(end -0.8636 0.4572)
			(stroke
				(width 0.1)
				(type default)
			)
			(layer "B.Fab")
		)
		(fp_line
			(start -0.8636 -0.4064)
			(end -1.1938 -0.4064)
			(stroke
				(width 0.1)
				(type default)
			)
			(layer "B.Fab")
		)
		(fp_line
			(start -0.8636 -0.4572)
			(end -0.8636 -0.4064)
			(stroke
				(width 0.1)
				(type default)
			)
			(layer "B.Fab")
		)
		(fp_line
			(start -1.1938 0.4064)
			(end -0.8636 0.4064)
			(stroke
				(width 0.1)
				(type default)
			)
			(layer "B.Fab")
		)
		(fp_line
			(start -1.1938 -0.4064)
			(end -1.1938 0.4064)
			(stroke
				(width 0.1)
				(type default)
			)
			(layer "B.Fab")
		)
		(pad "1" smd rect
			(at 0.7366 0 90)
			(size 0.7112 0.8128)
			(layers "B.Cu" "B.Mask" "B.Paste")
			(net "U412_D1")
		)
		(pad "2" smd rect
			(at -0.7366 0 90)
			(size 0.7112 0.8128)
			(layers "B.Cu" "B.Mask" "B.Paste")
			(net "GND")
		)
	)
	(footprint ""
		(layer "B.Cu")
		(at 9.922002 -167.771826 180)
		(property "Reference" "C53"
			(at 0 0 0)
			(layer "B.SilkS")
			(hide yes)
			(effects
				(font
					(size 1.27 1.27)
				)
				(justify mirror)
			)
		)
		(property "Value" ""
			(at 0 0 0)
			(layer "B.Fab")
			(effects
				(font
					(size 1.27 1.27)
				)
				(justify mirror)
			)
		)
		(duplicate_pad_numbers_are_jumpers no)
		(fp_line
			(start 0.7874 0.4064)
			(end 0.7874 -0.4064)
			(stroke
				(width 0.1524)
				(type default)
			)
			(layer "B.SilkS")
		)
		(fp_line
			(start 0.7874 -0.4064)
			(end -0.7874 -0.4064)
			(stroke
				(width 0.1524)
				(type default)
			)
			(layer "B.SilkS")
		)
		(fp_line
			(start -0.7874 0.4064)
			(end 0.7874 0.4064)
			(stroke
				(width 0.1524)
				(type default)
			)
			(layer "B.SilkS")
		)
		(fp_line
			(start -0.7874 -0.4064)
			(end -0.7874 0.4064)
			(stroke
				(width 0.1524)
				(type default)
			)
			(layer "B.SilkS")
		)
		(fp_line
			(start 0.67945 0.3048)
			(end 0.67945 -0.305054)
			(stroke
				(width 0.1)
				(type default)
			)
			(layer "B.Fab")
		)
		(fp_line
			(start 0.67945 -0.305054)
			(end 0.12065 -0.305054)
			(stroke
				(width 0.1)
				(type default)
			)
			(layer "B.Fab")
		)
		(fp_line
			(start 0.12065 0.3048)
			(end 0.67945 0.3048)
			(stroke
				(width 0.1)
				(type default)
			)
			(layer "B.Fab")
		)
		(fp_line
			(start 0.12065 0.2794)
			(end 0.12065 0.3048)
			(stroke
				(width 0.1)
				(type default)
			)
			(layer "B.Fab")
		)
		(fp_line
			(start 0.12065 -0.2794)
			(end -0.12065 -0.2794)
			(stroke
				(width 0.1)
				(type default)
			)
			(layer "B.Fab")
		)
		(fp_line
			(start 0.12065 -0.305054)
			(end 0.12065 -0.2794)
			(stroke
				(width 0.1)
				(type default)
			)
			(layer "B.Fab")
		)
		(fp_line
			(start -0.120396 0.3048)
			(end -0.120396 0.2794)
			(stroke
				(width 0.1)
				(type default)
			)
			(layer "B.Fab")
		)
		(fp_line
			(start -0.120396 0.2794)
			(end 0.12065 0.2794)
			(stroke
				(width 0.1)
				(type default)
			)
			(layer "B.Fab")
		)
		(fp_line
			(start -0.12065 -0.2794)
			(end -0.12065 -0.3048)
			(stroke
				(width 0.1)
				(type default)
			)
			(layer "B.Fab")
		)
		(fp_line
			(start -0.12065 -0.3048)
			(end -0.67945 -0.3048)
			(stroke
				(width 0.1)
				(type default)
			)
			(layer "B.Fab")
		)
		(fp_line
			(start -0.67945 0.3048)
			(end -0.120396 0.3048)
			(stroke
				(width 0.1)
				(type default)
			)
			(layer "B.Fab")
		)
		(fp_line
			(start -0.67945 -0.3048)
			(end -0.67945 0.3048)
			(stroke
				(width 0.1)
				(type default)
			)
			(layer "B.Fab")
		)
		(pad "1" smd circle
			(at 0.40005 0)
			(size 0 0)
			(layers "B.Cu" "B.Mask" "B.Paste")
			(net "P3V3_AUX")
		)
		(pad "2" smd circle
			(at -0.40005 0)
			(size 0 0)
			(layers "B.Cu" "B.Mask" "B.Paste")
			(net "GND")
		)
	)
	(footprint ""
		(layer "B.Cu")
		(at 32.131 -250.23699 -90)
		(property "Reference" "PR30"
			(at 0 0 90)
			(layer "B.SilkS")
			(hide yes)
			(effects
				(font
					(size 1.27 1.27)
				)
				(justify mirror)
			)
		)
		(property "Value" ""
			(at 0 0 90)
			(layer "B.Fab")
			(effects
				(font
					(size 1.27 1.27)
				)
				(justify mirror)
			)
		)
		(duplicate_pad_numbers_are_jumpers no)
		(fp_line
			(start -0.7874 0.4064)
			(end 0.7874 0.4064)
			(stroke
				(width 0.1524)
				(type default)
			)
			(layer "B.SilkS")
		)
		(fp_line
			(start 0.7874 0.4064)
			(end 0.7874 -0.4064)
			(stroke
				(width 0.1524)
				(type default)
			)
			(layer "B.SilkS")
		)
		(fp_line
			(start -0.7874 -0.4064)
			(end -0.7874 0.4064)
			(stroke
				(width 0.1524)
				(type default)
			)
			(layer "B.SilkS")
		)
		(fp_line
			(start 0.7874 -0.4064)
			(end -0.7874 -0.4064)
			(stroke
				(width 0.1524)
				(type default)
			)
			(layer "B.SilkS")
		)
		(fp_line
			(start -0.67945 0.3048)
			(end -0.120396 0.3048)
			(stroke
				(width 0.1)
				(type default)
			)
			(layer "B.Fab")
		)
		(fp_line
			(start -0.120396 0.3048)
			(end -0.120396 0.2794)
			(stroke
				(width 0.1)
				(type default)
			)
			(layer "B.Fab")
		)
		(fp_line
			(start 0.12065 0.3048)
			(end 0.67945 0.3048)
			(stroke
				(width 0.1)
				(type default)
			)
			(layer "B.Fab")
		)
		(fp_line
			(start 0.67945 0.3048)
			(end 0.67945 -0.305054)
			(stroke
				(width 0.1)
				(type default)
			)
			(layer "B.Fab")
		)
		(fp_line
			(start -0.120396 0.2794)
			(end 0.12065 0.2794)
			(stroke
				(width 0.1)
				(type default)
			)
			(layer "B.Fab")
		)
		(fp_line
			(start 0.12065 0.2794)
			(end 0.12065 0.3048)
			(stroke
				(width 0.1)
				(type default)
			)
			(layer "B.Fab")
		)
		(fp_line
			(start -0.12065 -0.2794)
			(end -0.12065 -0.3048)
			(stroke
				(width 0.1)
				(type default)
			)
			(layer "B.Fab")
		)
		(fp_line
			(start 0.12065 -0.2794)
			(end -0.12065 -0.2794)
			(stroke
				(width 0.1)
				(type default)
			)
			(layer "B.Fab")
		)
		(fp_line
			(start -0.67945 -0.3048)
			(end -0.67945 0.3048)
			(stroke
				(width 0.1)
				(type default)
			)
			(layer "B.Fab")
		)
		(fp_line
			(start -0.12065 -0.3048)
			(end -0.67945 -0.3048)
			(stroke
				(width 0.1)
				(type default)
			)
			(layer "B.Fab")
		)
		(fp_line
			(start 0.12065 -0.305054)
			(end 0.12065 -0.2794)
			(stroke
				(width 0.1)
				(type default)
			)
			(layer "B.Fab")
		)
		(fp_line
			(start 0.67945 -0.305054)
			(end 0.12065 -0.305054)
			(stroke
				(width 0.1)
				(type default)
			)
			(layer "B.Fab")
		)
		(pad "1" smd circle
			(at 0.40005 0 90)
			(size 0 0)
			(layers "B.Cu" "B.Mask" "B.Paste")
			(net "FAN_1_CS")
		)
		(pad "2" smd circle
			(at -0.40005 0 90)
			(size 0 0)
			(layers "B.Cu" "B.Mask" "B.Paste")
			(net "GND")
		)
	)
)
